(kicad_pcb
	(version 20260206)
	(generator "pcbnew")
	(generator_version "10.0")
	(general
		(thickness 1.6)
		(legacy_teardrops no)
	)
	(paper "A4")
	(title_block
		(title "Bryce Canyon_LED_16347-1_OCP.brd")
		(comment 1 "Bryce Canyon / footprints 1-7 of 49")
	)
	(layers
		(0 "F.Cu" signal "TOP")
		(2 "B.Cu" signal "BOTTOM")
		(9 "F.Adhes" user "F.Adhesive")
		(11 "B.Adhes" user "B.Adhesive")
		(13 "F.Paste" user "Package Geometry/Pastemask Top")
		(15 "B.Paste" user "Package Geometry/Pastemask Bottom")
		(5 "F.SilkS" user "Ref Des/Silkscreen Top")
		(7 "B.SilkS" user "Ref Des/Silkscreen Bottom")
		(1 "F.Mask" user "Board Geometry/Soldermask Top")
		(3 "B.Mask" user "Board Geometry/Soldermask Bottom")
		(17 "Dwgs.User" user "User.Drawings")
		(19 "Cmts.User" user "User.Comments")
		(21 "Eco1.User" user "User.Eco1")
		(23 "Eco2.User" user "User.Eco2")
		(25 "Edge.Cuts" user "Board Geometry/Outline")
		(27 "Margin" user)
		(31 "F.CrtYd" user "Package Geometry/Place Bound Top")
		(29 "B.CrtYd" user "Package Geometry/Place Bound Bottom")
		(35 "F.Fab" user "Ref Des/Assembly Top")
		(33 "B.Fab" user "Ref Des/Assembly Bottom")
	)
	(footprint ""
		(layer "F.Cu")
		(at 180.874924 -4.999736)
		(property "Reference" ""
			(at 0 0 0)
			(layer "F.SilkS")
			(hide yes)
			(effects
				(font
					(size 1.27 1.27)
				)
			)
		)
		(property "Value" "*"
			(at -4.0767 1.0668 0)
			(unlocked yes)
			(layer "F.Fab")
			(hide yes)
			(effects
				(font
					(size 1.016 1.016)
					(thickness 0.1524)
				)
			)
		)
		(duplicate_pad_numbers_are_jumpers no)
		(fp_poly
			(pts
				(arc
					(start 3.3147 0)
					(mid -3.3147 0)
					(end 3.3147 0)
				)
			)
			(stroke
				(width 0)
				(type default)
			)
			(fill no)
			(layer "B.CrtYd")
		)
		(fp_poly
			(pts
				(arc
					(start 3.3147 0)
					(mid -3.3147 0)
					(end 3.3147 0)
				)
			)
			(stroke
				(width 0)
				(type default)
			)
			(fill no)
			(layer "F.CrtYd")
		)
		(fp_poly
			(pts
				(arc
					(start 3.3147 0)
					(mid -3.3147 0)
					(end 3.3147 0)
				)
			)
			(stroke
				(width 0)
				(type default)
			)
			(fill no)
			(layer "B.Fab")
		)
		(fp_poly
			(pts
				(arc
					(start 3.3147 0)
					(mid -3.3147 0)
					(end 3.3147 0)
				)
			)
			(stroke
				(width 0)
				(type default)
			)
			(fill no)
			(layer "F.Fab")
		)
		(pad "1" thru_hole circle
			(at 0 0)
			(size 6.0198 6.0198)
			(drill 2.5654)
			(layers "*.Cu" "*.Mask")
			(remove_unused_layers no)
			(net "Net_8")
			(clearance -1.2192)
		)
		(zone
			(layers "F.Cu" "B.Cu")
			(hatch none 0.5)
			(connect_pads
				(clearance 0)
			)
			(min_thickness 0.25)
			(keepout
				(tracks not_allowed)
				(vias allowed)
				(pads allowed)
				(copperpour not_allowed)
				(footprints allowed)
			)
			(placement
				(enabled no)
				(sheetname "")
			)
			(fill
				(thermal_gap 0.5)
				(thermal_bridge_width 0.5)
				(island_removal_mode 0)
			)
			(polygon
				(pts
					(arc
						(start 183.884824 -4.999736)
						(mid 177.865024 -4.999736)
						(end 183.884824 -4.999736)
					)
				)
			)
		)
	)
	(footprint ""
		(layer "F.Cu")
		(at 171.349924 -14.99997)
		(property "Reference" "LED6"
			(at 0 0 0)
			(layer "F.SilkS")
			(hide yes)
			(effects
				(font
					(size 1.27 1.27)
				)
			)
		)
		(property "Value" "LED-BY-19-GP"
			(at -2.132076 1.414018 0)
			(unlocked yes)
			(layer "F.Fab")
			(hide yes)
			(effects
				(font
					(size 1.016 1.016)
					(thickness 0.1524)
				)
			)
		)
		(property "Device Type" "LED-1615-4PH26"
			(at -2.132076 -0.109982 0)
			(unlocked yes)
			(layer "F.Fab")
			(hide yes)
			(effects
				(font
					(size 1.016 1.016)
					(thickness 0.1524)
				)
			)
		)
		(duplicate_pad_numbers_are_jumpers no)
		(fp_line
			(start -1.2954 0.254)
			(end -1.2954 1.6002)
			(stroke
				(width 0.508)
				(type default)
			)
			(layer "F.SilkS")
		)
		(fp_line
			(start -1.2954 1.6002)
			(end 1.2954 1.6002)
			(stroke
				(width 0.508)
				(type default)
			)
			(layer "F.SilkS")
		)
		(fp_line
			(start -1.1176 -1.4224)
			(end 1.1176 -1.4224)
			(stroke
				(width 0.1524)
				(type default)
			)
			(layer "F.SilkS")
		)
		(fp_line
			(start -1.1176 1.4224)
			(end -1.1176 -1.4224)
			(stroke
				(width 0.1524)
				(type default)
			)
			(layer "F.SilkS")
		)
		(fp_line
			(start 1.1176 -1.4224)
			(end 1.1176 1.4224)
			(stroke
				(width 0.1524)
				(type default)
			)
			(layer "F.SilkS")
		)
		(fp_line
			(start 1.1176 1.4224)
			(end -1.1176 1.4224)
			(stroke
				(width 0.1524)
				(type default)
			)
			(layer "F.SilkS")
		)
		(fp_line
			(start 1.2954 1.6002)
			(end 1.2954 0.254)
			(stroke
				(width 0.508)
				(type default)
			)
			(layer "F.SilkS")
		)
		(fp_rect
			(start -0.7493 0.8001)
			(end 0.7493 -0.8001)
			(stroke
				(width 0)
				(type default)
			)
			(fill no)
			(layer "F.CrtYd")
		)
		(fp_poly
			(pts
				(xy -1.3716 1.6764) (xy -1.3716 -1.6764) (xy 1.3716 -1.6764) (xy 1.3716 0.0635) (xy 0.7493 0.0635)
				(xy 0.7493 -0.8001) (xy -0.7493 -0.8001) (xy -0.7493 0.8001) (xy 0.7493 0.8001) (xy 0.7493 0.0762)
				(xy 1.3716 0.0762) (xy 1.3716 1.6764)
			)
			(stroke
				(width 0)
				(type default)
			)
			(fill no)
			(layer "F.CrtYd")
		)
		(fp_rect
			(start -1.3716 1.6764)
			(end 1.3716 -1.6764)
			(stroke
				(width 0)
				(type default)
			)
			(fill no)
			(layer "F.Fab")
		)
		(pad "1" smd rect
			(at 0.50038 -0.73025)
			(size 0.7112 0.8636)
			(layers "F.Cu" "F.Mask" "F.Paste")
			(net "DRV_ACT_29_35")
		)
		(pad "2" smd rect
			(at -0.50038 -0.73025)
			(size 0.7112 0.8636)
			(layers "F.Cu" "F.Mask" "F.Paste")
			(net "FLT_HDD29_35")
		)
		(pad "3" smd rect
			(at 0.50038 0.73025)
			(size 0.7112 0.8636)
			(layers "F.Cu" "F.Mask" "F.Paste")
			(net "DRV_ACT_29_35_N")
		)
		(pad "4" smd rect
			(at -0.50038 0.73025)
			(size 0.7112 0.8636)
			(layers "F.Cu" "F.Mask" "F.Paste")
			(net "FLT_HDD29_35_N")
		)
	)
	(footprint ""
		(layer "F.Cu")
		(at 108.249974 -14.99997)
		(property "Reference" "LED4"
			(at 0 0 0)
			(layer "F.SilkS")
			(hide yes)
			(effects
				(font
					(size 1.27 1.27)
				)
			)
		)
		(property "Value" "LED-BY-19-GP"
			(at -2.132076 1.414018 0)
			(unlocked yes)
			(layer "F.Fab")
			(hide yes)
			(effects
				(font
					(size 1.016 1.016)
					(thickness 0.1524)
				)
			)
		)
		(property "Device Type" "LED-1615-4PH26"
			(at -2.132076 -0.109982 0)
			(unlocked yes)
			(layer "F.Fab")
			(hide yes)
			(effects
				(font
					(size 1.016 1.016)
					(thickness 0.1524)
				)
			)
		)
		(duplicate_pad_numbers_are_jumpers no)
		(fp_line
			(start -1.2954 0.254)
			(end -1.2954 1.6002)
			(stroke
				(width 0.508)
				(type default)
			)
			(layer "F.SilkS")
		)
		(fp_line
			(start -1.2954 1.6002)
			(end 1.2954 1.6002)
			(stroke
				(width 0.508)
				(type default)
			)
			(layer "F.SilkS")
		)
		(fp_line
			(start -1.1176 -1.4224)
			(end 1.1176 -1.4224)
			(stroke
				(width 0.1524)
				(type default)
			)
			(layer "F.SilkS")
		)
		(fp_line
			(start -1.1176 1.4224)
			(end -1.1176 -1.4224)
			(stroke
				(width 0.1524)
				(type default)
			)
			(layer "F.SilkS")
		)
		(fp_line
			(start 1.1176 -1.4224)
			(end 1.1176 1.4224)
			(stroke
				(width 0.1524)
				(type default)
			)
			(layer "F.SilkS")
		)
		(fp_line
			(start 1.1176 1.4224)
			(end -1.1176 1.4224)
			(stroke
				(width 0.1524)
				(type default)
			)
			(layer "F.SilkS")
		)
		(fp_line
			(start 1.2954 1.6002)
			(end 1.2954 0.254)
			(stroke
				(width 0.508)
				(type default)
			)
			(layer "F.SilkS")
		)
		(fp_rect
			(start -0.7493 0.8001)
			(end 0.7493 -0.8001)
			(stroke
				(width 0)
				(type default)
			)
			(fill no)
			(layer "F.CrtYd")
		)
		(fp_poly
			(pts
				(xy -1.3716 1.6764) (xy -1.3716 -1.6764) (xy 1.3716 -1.6764) (xy 1.3716 0.0635) (xy 0.7493 0.0635)
				(xy 0.7493 -0.8001) (xy -0.7493 -0.8001) (xy -0.7493 0.8001) (xy 0.7493 0.8001) (xy 0.7493 0.0762)
				(xy 1.3716 0.0762) (xy 1.3716 1.6764)
			)
			(stroke
				(width 0)
				(type default)
			)
			(fill no)
			(layer "F.CrtYd")
		)
		(fp_rect
			(start -1.3716 1.6764)
			(end 1.3716 -1.6764)
			(stroke
				(width 0)
				(type default)
			)
			(fill no)
			(layer "F.Fab")
		)
		(pad "1" smd rect
			(at 0.50038 -0.73025)
			(size 0.7112 0.8636)
			(layers "F.Cu" "F.Mask" "F.Paste")
			(net "DRV_ACT_27_33")
		)
		(pad "2" smd rect
			(at -0.50038 -0.73025)
			(size 0.7112 0.8636)
			(layers "F.Cu" "F.Mask" "F.Paste")
			(net "FLT_HDD27_33")
		)
		(pad "3" smd rect
			(at 0.50038 0.73025)
			(size 0.7112 0.8636)
			(layers "F.Cu" "F.Mask" "F.Paste")
			(net "DRV_ACT_27_33_N")
		)
		(pad "4" smd rect
			(at -0.50038 0.73025)
			(size 0.7112 0.8636)
			(layers "F.Cu" "F.Mask" "F.Paste")
			(net "FLT_HDD27_33_N")
		)
	)
	(footprint ""
		(layer "F.Cu")
		(at 76.700126 -14.99997)
		(property "Reference" "LED3"
			(at 0 0 0)
			(layer "F.SilkS")
			(hide yes)
			(effects
				(font
					(size 1.27 1.27)
				)
			)
		)
		(property "Value" "LED-BY-19-GP"
			(at -2.132076 1.414018 0)
			(unlocked yes)
			(layer "F.Fab")
			(hide yes)
			(effects
				(font
					(size 1.016 1.016)
					(thickness 0.1524)
				)
			)
		)
		(property "Device Type" "LED-1615-4PH26"
			(at -2.132076 -0.109982 0)
			(unlocked yes)
			(layer "F.Fab")
			(hide yes)
			(effects
				(font
					(size 1.016 1.016)
					(thickness 0.1524)
				)
			)
		)
		(duplicate_pad_numbers_are_jumpers no)
		(fp_line
			(start -1.2954 0.254)
			(end -1.2954 1.6002)
			(stroke
				(width 0.508)
				(type default)
			)
			(layer "F.SilkS")
		)
		(fp_line
			(start -1.2954 1.6002)
			(end 1.2954 1.6002)
			(stroke
				(width 0.508)
				(type default)
			)
			(layer "F.SilkS")
		)
		(fp_line
			(start -1.1176 -1.4224)
			(end 1.1176 -1.4224)
			(stroke
				(width 0.1524)
				(type default)
			)
			(layer "F.SilkS")
		)
		(fp_line
			(start -1.1176 1.4224)
			(end -1.1176 -1.4224)
			(stroke
				(width 0.1524)
				(type default)
			)
			(layer "F.SilkS")
		)
		(fp_line
			(start 1.1176 -1.4224)
			(end 1.1176 1.4224)
			(stroke
				(width 0.1524)
				(type default)
			)
			(layer "F.SilkS")
		)
		(fp_line
			(start 1.1176 1.4224)
			(end -1.1176 1.4224)
			(stroke
				(width 0.1524)
				(type default)
			)
			(layer "F.SilkS")
		)
		(fp_line
			(start 1.2954 1.6002)
			(end 1.2954 0.254)
			(stroke
				(width 0.508)
				(type default)
			)
			(layer "F.SilkS")
		)
		(fp_rect
			(start -0.7493 0.8001)
			(end 0.7493 -0.8001)
			(stroke
				(width 0)
				(type default)
			)
			(fill no)
			(layer "F.CrtYd")
		)
		(fp_poly
			(pts
				(xy -1.3716 1.6764) (xy -1.3716 -1.6764) (xy 1.3716 -1.6764) (xy 1.3716 0.0635) (xy 0.7493 0.0635)
				(xy 0.7493 -0.8001) (xy -0.7493 -0.8001) (xy -0.7493 0.8001) (xy 0.7493 0.8001) (xy 0.7493 0.0762)
				(xy 1.3716 0.0762) (xy 1.3716 1.6764)
			)
			(stroke
				(width 0)
				(type default)
			)
			(fill no)
			(layer "F.CrtYd")
		)
		(fp_rect
			(start -1.3716 1.6764)
			(end 1.3716 -1.6764)
			(stroke
				(width 0)
				(type default)
			)
			(fill no)
			(layer "F.Fab")
		)
		(pad "1" smd rect
			(at 0.50038 -0.73025)
			(size 0.7112 0.8636)
			(layers "F.Cu" "F.Mask" "F.Paste")
			(net "DRV_ACT_26_32")
		)
		(pad "2" smd rect
			(at -0.50038 -0.73025)
			(size 0.7112 0.8636)
			(layers "F.Cu" "F.Mask" "F.Paste")
			(net "FLT_HDD26_32")
		)
		(pad "3" smd rect
			(at 0.50038 0.73025)
			(size 0.7112 0.8636)
			(layers "F.Cu" "F.Mask" "F.Paste")
			(net "DRV_ACT_26_32_N")
		)
		(pad "4" smd rect
			(at -0.50038 0.73025)
			(size 0.7112 0.8636)
			(layers "F.Cu" "F.Mask" "F.Paste")
			(net "FLT_HDD26_32_N")
		)
	)
	(footprint ""
		(layer "F.Cu")
		(at 4.12496 -4.999736)
		(property "Reference" ""
			(at 0 0 0)
			(layer "F.SilkS")
			(hide yes)
			(effects
				(font
					(size 1.27 1.27)
				)
			)
		)
		(property "Value" "*"
			(at -4.0767 1.0668 0)
			(unlocked yes)
			(layer "F.Fab")
			(hide yes)
			(effects
				(font
					(size 1.016 1.016)
					(thickness 0.1524)
				)
			)
		)
		(duplicate_pad_numbers_are_jumpers no)
		(fp_poly
			(pts
				(arc
					(start 3.3147 0)
					(mid -3.3147 0)
					(end 3.3147 0)
				)
			)
			(stroke
				(width 0)
				(type default)
			)
			(fill no)
			(layer "B.CrtYd")
		)
		(fp_poly
			(pts
				(arc
					(start 3.3147 0)
					(mid -3.3147 0)
					(end 3.3147 0)
				)
			)
			(stroke
				(width 0)
				(type default)
			)
			(fill no)
			(layer "F.CrtYd")
		)
		(fp_poly
			(pts
				(arc
					(start 3.3147 0)
					(mid -3.3147 0)
					(end 3.3147 0)
				)
			)
			(stroke
				(width 0)
				(type default)
			)
			(fill no)
			(layer "B.Fab")
		)
		(fp_poly
			(pts
				(arc
					(start 3.3147 0)
					(mid -3.3147 0)
					(end 3.3147 0)
				)
			)
			(stroke
				(width 0)
				(type default)
			)
			(fill no)
			(layer "F.Fab")
		)
		(pad "1" thru_hole circle
			(at 0 0)
			(size 6.0198 6.0198)
			(drill 2.5654)
			(layers "*.Cu" "*.Mask")
			(remove_unused_layers no)
			(net "Net_5")
			(clearance -1.2192)
		)
		(zone
			(layers "F.Cu" "B.Cu")
			(hatch none 0.5)
			(connect_pads
				(clearance 0)
			)
			(min_thickness 0.25)
			(keepout
				(tracks not_allowed)
				(vias allowed)
				(pads allowed)
				(copperpour not_allowed)
				(footprints allowed)
			)
			(placement
				(enabled no)
				(sheetname "")
			)
			(fill
				(thermal_gap 0.5)
				(thermal_bridge_width 0.5)
				(island_removal_mode 0)
			)
			(polygon
				(pts
					(arc
						(start 7.13486 -4.999736)
						(mid 1.11506 -4.999736)
						(end 7.13486 -4.999736)
					)
				)
			)
		)
	)
	(footprint ""
		(layer "F.Cu")
		(at 76.699872 -4.99999)
		(property "Reference" ""
			(at 0 0 0)
			(layer "F.SilkS")
			(hide yes)
			(effects
				(font
					(size 1.27 1.27)
				)
			)
		)
		(property "Value" "*"
			(at -4.0767 1.0668 0)
			(unlocked yes)
			(layer "F.Fab")
			(hide yes)
			(effects
				(font
					(size 1.016 1.016)
					(thickness 0.1524)
				)
			)
		)
		(duplicate_pad_numbers_are_jumpers no)
		(fp_poly
			(pts
				(arc
					(start 3.3147 0)
					(mid -3.3147 0)
					(end 3.3147 0)
				)
			)
			(stroke
				(width 0)
				(type default)
			)
			(fill no)
			(layer "B.CrtYd")
		)
		(fp_poly
			(pts
				(arc
					(start 3.3147 0)
					(mid -3.3147 0)
					(end 3.3147 0)
				)
			)
			(stroke
				(width 0)
				(type default)
			)
			(fill no)
			(layer "F.CrtYd")
		)
		(fp_poly
			(pts
				(arc
					(start 3.3147 0)
					(mid -3.3147 0)
					(end 3.3147 0)
				)
			)
			(stroke
				(width 0)
				(type default)
			)
			(fill no)
			(layer "B.Fab")
		)
		(fp_poly
			(pts
				(arc
					(start 3.3147 0)
					(mid -3.3147 0)
					(end 3.3147 0)
				)
			)
			(stroke
				(width 0)
				(type default)
			)
			(fill no)
			(layer "F.Fab")
		)
		(pad "1" thru_hole circle
			(at 0 0)
			(size 6.0198 6.0198)
			(drill 2.5654)
			(layers "*.Cu" "*.Mask")
			(remove_unused_layers no)
			(net "Net_6")
			(clearance -1.2192)
		)
		(zone
			(layers "F.Cu" "B.Cu")
			(hatch none 0.5)
			(connect_pads
				(clearance 0)
			)
			(min_thickness 0.25)
			(keepout
				(tracks not_allowed)
				(vias allowed)
				(pads allowed)
				(copperpour not_allowed)
				(footprints allowed)
			)
			(placement
				(enabled no)
				(sheetname "")
			)
			(fill
				(thermal_gap 0.5)
				(thermal_bridge_width 0.5)
				(island_removal_mode 0)
			)
			(polygon
				(pts
					(arc
						(start 79.709772 -4.99999)
						(mid 73.689972 -4.99999)
						(end 79.709772 -4.99999)
					)
				)
			)
		)
	)
	(footprint ""
		(layer "F.Cu")
		(at 13.599922 -14.99997)
		(property "Reference" "LED1"
			(at 0 0 0)
			(layer "F.SilkS")
			(hide yes)
			(effects
				(font
					(size 1.27 1.27)
				)
			)
		)
		(property "Value" "LED-BY-19-GP"
			(at -2.132076 1.414018 0)
			(unlocked yes)
			(layer "F.Fab")
			(hide yes)
			(effects
				(font
					(size 1.016 1.016)
					(thickness 0.1524)
				)
			)
		)
		(property "Device Type" "LED-1615-4PH26"
			(at -2.132076 -0.109982 0)
			(unlocked yes)
			(layer "F.Fab")
			(hide yes)
			(effects
				(font
					(size 1.016 1.016)
					(thickness 0.1524)
				)
			)
		)
		(duplicate_pad_numbers_are_jumpers no)
		(fp_line
			(start -1.2954 0.254)
			(end -1.2954 1.6002)
			(stroke
				(width 0.508)
				(type default)
			)
			(layer "F.SilkS")
		)
		(fp_line
			(start -1.2954 1.6002)
			(end 1.2954 1.6002)
			(stroke
				(width 0.508)
				(type default)
			)
			(layer "F.SilkS")
		)
		(fp_line
			(start -1.1176 -1.4224)
			(end 1.1176 -1.4224)
			(stroke
				(width 0.1524)
				(type default)
			)
			(layer "F.SilkS")
		)
		(fp_line
			(start -1.1176 1.4224)
			(end -1.1176 -1.4224)
			(stroke
				(width 0.1524)
				(type default)
			)
			(layer "F.SilkS")
		)
		(fp_line
			(start 1.1176 -1.4224)
			(end 1.1176 1.4224)
			(stroke
				(width 0.1524)
				(type default)
			)
			(layer "F.SilkS")
		)
		(fp_line
			(start 1.1176 1.4224)
			(end -1.1176 1.4224)
			(stroke
				(width 0.1524)
				(type default)
			)
			(layer "F.SilkS")
		)
		(fp_line
			(start 1.2954 1.6002)
			(end 1.2954 0.254)
			(stroke
				(width 0.508)
				(type default)
			)
			(layer "F.SilkS")
		)
		(fp_rect
			(start -0.7493 0.8001)
			(end 0.7493 -0.8001)
			(stroke
				(width 0)
				(type default)
			)
			(fill no)
			(layer "F.CrtYd")
		)
		(fp_poly
			(pts
				(xy -1.3716 1.6764) (xy -1.3716 -1.6764) (xy 1.3716 -1.6764) (xy 1.3716 0.0635) (xy 0.7493 0.0635)
				(xy 0.7493 -0.8001) (xy -0.7493 -0.8001) (xy -0.7493 0.8001) (xy 0.7493 0.8001) (xy 0.7493 0.0762)
				(xy 1.3716 0.0762) (xy 1.3716 1.6764)
			)
			(stroke
				(width 0)
				(type default)
			)
			(fill no)
			(layer "F.CrtYd")
		)
		(fp_rect
			(start -1.3716 1.6764)
			(end 1.3716 -1.6764)
			(stroke
				(width 0)
				(type default)
			)
			(fill no)
			(layer "F.Fab")
		)
		(pad "1" smd rect
			(at 0.50038 -0.73025)
			(size 0.7112 0.8636)
			(layers "F.Cu" "F.Mask" "F.Paste")
			(net "DRV_ACT_24_30")
		)
		(pad "2" smd rect
			(at -0.50038 -0.73025)
			(size 0.7112 0.8636)
			(layers "F.Cu" "F.Mask" "F.Paste")
			(net "FLT_HDD24_30")
		)
		(pad "3" smd rect
			(at 0.50038 0.73025)
			(size 0.7112 0.8636)
			(layers "F.Cu" "F.Mask" "F.Paste")
			(net "DRV_ACT_24_30_N")
		)
		(pad "4" smd rect
			(at -0.50038 0.73025)
			(size 0.7112 0.8636)
			(layers "F.Cu" "F.Mask" "F.Paste")
			(net "FLT_HDD24_30_N")
		)
	)
)
